(kicad_pcb
	(version 20260206)
	(generator "pcbnew")
	(generator_version "10.0")
	(general
		(thickness 1.6)
		(legacy_teardrops no)
	)
	(paper "A4")
	(title_block
		(title "04192023_DAF0TMB3IC0_F0TG_MB_C_brd_V02_OCP.brd")
		(comment 1 "Grand Teton / footprint 3955 of 8354 (U25), pads 760-866 of 6102")
	)
	(layers
		(0 "F.Cu" signal "TOP")
		(4 "In1.Cu" signal "GND")
		(6 "In2.Cu" signal "IN1")
		(8 "In3.Cu" signal "GND1")
		(10 "In4.Cu" signal "IN2")
		(12 "In5.Cu" signal "GND2")
		(14 "In6.Cu" signal "IN3")
		(16 "In7.Cu" signal "GND3")
		(18 "In8.Cu" signal "VCC")
		(20 "In9.Cu" signal "VCC1")
		(22 "In10.Cu" signal "GND4")
		(24 "In11.Cu" signal "IN4")
		(26 "In12.Cu" signal "GND5")
		(28 "In13.Cu" signal "IN5")
		(30 "In14.Cu" signal "GND6")
		(32 "In15.Cu" signal "IN6")
		(34 "In16.Cu" signal "GND7")
		(2 "B.Cu" signal "BOTTOM")
		(9 "F.Adhes" user "F.Adhesive")
		(11 "B.Adhes" user "B.Adhesive")
		(13 "F.Paste" user "Package Geometry/Pastemask Top")
		(15 "B.Paste" user "Package Geometry/Pastemask Bottom")
		(5 "F.SilkS" user "Ref Des/Silkscreen Top")
		(7 "B.SilkS" user "Ref Des/Silkscreen Bottom")
		(1 "F.Mask" user "Board Geometry/Soldermask Top")
		(3 "B.Mask" user "Board Geometry/Soldermask Bottom")
		(17 "Dwgs.User" user "User.Drawings")
		(19 "Cmts.User" user "User.Comments")
		(21 "Eco1.User" user "User.Eco1")
		(23 "Eco2.User" user "User.Eco2")
		(25 "Edge.Cuts" user "Board Geometry/Outline")
		(27 "Margin" user)
		(31 "F.CrtYd" user "Package Geometry/Place Bound Top")
		(29 "B.CrtYd" user "Package Geometry/Place Bound Bottom")
		(35 "F.Fab" user "Ref Des/Assembly Top")
		(33 "B.Fab" user "Ref Des/Assembly Bottom")
	)
	(footprint ""
		(layer "F.Cu")
		(at 359.867962 -258.880102 180)
		(property "Reference" "U25"
			(at -45.78477 -62.086744 0)
			(unlocked yes)
			(layer "F.SilkS")
			(effects
				(font
					(size 0.7874 0.5842)
					(thickness 0.1524)
				)
			)
		)
		(property "Value" ""
			(at 0 0 180)
			(layer "F.Fab")
			(effects
				(font
					(size 1.27 1.27)
				)
			)
		)
		(duplicate_pad_numbers_are_jumpers no)
		(pad "AK52" smd circle
			(at 13.310108 -13.320014 180)
			(size 0.450088 0.450088)
			(layers "F.Cu" "F.Mask" "F.Paste")
			(net "PVDDCR_CPU0_P0")
		)
		(pad "AK53" smd circle
			(at 14.249908 -13.320014 180)
			(size 0.450088 0.450088)
			(layers "F.Cu" "F.Mask" "F.Paste")
			(net "PVDDCR_CPU0_P0")
		)
		(pad "AK54" smd circle
			(at 15.189962 -13.320014 180)
			(size 0.450088 0.450088)
			(layers "F.Cu" "F.Mask" "F.Paste")
			(net "GND")
		)
		(pad "AK55" smd circle
			(at 16.130016 -13.320014 180)
			(size 0.450088 0.450088)
			(layers "F.Cu" "F.Mask" "F.Paste")
			(net "M_C_CPU0_SA_CB<1>")
		)
		(pad "AK56" smd circle
			(at 17.07007 -13.320014 180)
			(size 0.450088 0.450088)
			(layers "F.Cu" "F.Mask" "F.Paste")
			(net "M_C_CPU0_SA_CB<2>")
		)
		(pad "AK57" smd circle
			(at 18.010124 -13.320014 180)
			(size 0.450088 0.450088)
			(layers "F.Cu" "F.Mask" "F.Paste")
			(net "GND")
		)
		(pad "AK58" smd circle
			(at 18.949924 -13.320014 180)
			(size 0.450088 0.450088)
			(layers "F.Cu" "F.Mask" "F.Paste")
			(net "M_D_CPU0_SA_CB<1>")
		)
		(pad "AK59" smd circle
			(at 19.889978 -13.320014 180)
			(size 0.450088 0.450088)
			(layers "F.Cu" "F.Mask" "F.Paste")
			(net "GND")
		)
		(pad "AK60" smd circle
			(at 20.830032 -13.320014 180)
			(size 0.450088 0.450088)
			(layers "F.Cu" "F.Mask" "F.Paste")
			(net "M_D_CPU0_SA_CB<2>")
		)
		(pad "AK61" smd circle
			(at 21.770086 -13.320014 180)
			(size 0.450088 0.450088)
			(layers "F.Cu" "F.Mask" "F.Paste")
			(net "GND")
		)
		(pad "AK62" smd circle
			(at 22.709886 -13.320014 180)
			(size 0.450088 0.450088)
			(layers "F.Cu" "F.Mask" "F.Paste")
			(net "M_B_CPU0_SA_CB<1>")
		)
		(pad "AK63" smd circle
			(at 23.64994 -13.320014 180)
			(size 0.450088 0.450088)
			(layers "F.Cu" "F.Mask" "F.Paste")
			(net "M_B_CPU0_SA_CB<2>")
		)
		(pad "AK64" smd circle
			(at 24.589994 -13.320014 180)
			(size 0.450088 0.450088)
			(layers "F.Cu" "F.Mask" "F.Paste")
			(net "GND")
		)
		(pad "AK65" smd circle
			(at 25.530048 -13.320014 180)
			(size 0.450088 0.450088)
			(layers "F.Cu" "F.Mask" "F.Paste")
			(net "M_F_CPU0_SA_CB<1>")
		)
		(pad "AK66" smd circle
			(at 26.470102 -13.320014 180)
			(size 0.450088 0.450088)
			(layers "F.Cu" "F.Mask" "F.Paste")
			(net "GND")
		)
		(pad "AK67" smd circle
			(at 27.409902 -13.320014 180)
			(size 0.450088 0.450088)
			(layers "F.Cu" "F.Mask" "F.Paste")
			(net "M_F_CPU0_SA_CB<2>")
		)
		(pad "AK68" smd circle
			(at 28.349956 -13.320014 180)
			(size 0.450088 0.450088)
			(layers "F.Cu" "F.Mask" "F.Paste")
			(net "GND")
		)
		(pad "AK69" smd circle
			(at 29.29001 -13.320014 180)
			(size 0.450088 0.450088)
			(layers "F.Cu" "F.Mask" "F.Paste")
			(net "M_E_CPU0_SA_CB<1>")
		)
		(pad "AK70" smd circle
			(at 30.230064 -13.320014 180)
			(size 0.450088 0.450088)
			(layers "F.Cu" "F.Mask" "F.Paste")
			(net "M_E_CPU0_SA_CB<2>")
		)
		(pad "AK71" smd circle
			(at 31.170118 -13.320014 180)
			(size 0.450088 0.450088)
			(layers "F.Cu" "F.Mask" "F.Paste")
			(net "GND")
		)
		(pad "AK72" smd circle
			(at 32.109918 -13.320014 180)
			(size 0.450088 0.450088)
			(layers "F.Cu" "F.Mask" "F.Paste")
			(net "M_A_CPU0_SA_CB<1>")
		)
		(pad "AK73" smd circle
			(at 33.049972 -13.320014 180)
			(size 0.450088 0.450088)
			(layers "F.Cu" "F.Mask" "F.Paste")
			(net "GND")
		)
		(pad "AK74" smd circle
			(at 33.990026 -13.320014 180)
			(size 0.450088 0.450088)
			(layers "F.Cu" "F.Mask" "F.Paste")
			(net "M_A_CPU0_SA_CB<2>")
		)
		(pad "AL1" smd circle
			(at -34.159952 -12.510008 180)
			(size 0.450088 0.450088)
			(layers "F.Cu" "F.Mask" "F.Paste")
			(net "GND")
		)
		(pad "AL2" smd circle
			(at -33.219898 -12.510008 180)
			(size 0.450088 0.450088)
			(layers "F.Cu" "F.Mask" "F.Paste")
			(net "M_G_CPU0_SA_DQS_DP<4>")
		)
		(pad "AL3" smd circle
			(at -32.280098 -12.510008 180)
			(size 0.450088 0.450088)
			(layers "F.Cu" "F.Mask" "F.Paste")
			(net "M_G_CPU0_SA_CB<3>")
		)
		(pad "AL4" smd circle
			(at -31.340044 -12.510008 180)
			(size 0.450088 0.450088)
			(layers "F.Cu" "F.Mask" "F.Paste")
			(net "GND")
		)
		(pad "AL5" smd circle
			(at -30.39999 -12.510008 180)
			(size 0.450088 0.450088)
			(layers "F.Cu" "F.Mask" "F.Paste")
			(net "M_K_CPU0_SA_DQS_DP<4>")
		)
		(pad "AL6" smd circle
			(at -29.459936 -12.510008 180)
			(size 0.450088 0.450088)
			(layers "F.Cu" "F.Mask" "F.Paste")
			(net "GND")
		)
		(pad "AL7" smd circle
			(at -28.519882 -12.510008 180)
			(size 0.450088 0.450088)
			(layers "F.Cu" "F.Mask" "F.Paste")
			(net "M_K_CPU0_SA_CB<3>")
		)
		(pad "AL8" smd circle
			(at -27.580082 -12.510008 180)
			(size 0.450088 0.450088)
			(layers "F.Cu" "F.Mask" "F.Paste")
			(net "GND")
		)
		(pad "AL9" smd circle
			(at -26.640028 -12.510008 180)
			(size 0.450088 0.450088)
			(layers "F.Cu" "F.Mask" "F.Paste")
			(net "M_L_CPU0_SA_DQS_DP<4>")
		)
		(pad "AL10" smd circle
			(at -25.699974 -12.510008 180)
			(size 0.450088 0.450088)
			(layers "F.Cu" "F.Mask" "F.Paste")
			(net "M_L_CPU0_SA_CB<3>")
		)
		(pad "AL11" smd circle
			(at -24.75992 -12.510008 180)
			(size 0.450088 0.450088)
			(layers "F.Cu" "F.Mask" "F.Paste")
			(net "GND")
		)
		(pad "AL12" smd circle
			(at -23.82012 -12.510008 180)
			(size 0.450088 0.450088)
			(layers "F.Cu" "F.Mask" "F.Paste")
			(net "M_H_CPU0_SA_DQS_DP<4>")
		)
		(pad "AL13" smd circle
			(at -22.880066 -12.510008 180)
			(size 0.450088 0.450088)
			(layers "F.Cu" "F.Mask" "F.Paste")
			(net "GND")
		)
		(pad "AL14" smd circle
			(at -21.940012 -12.510008 180)
			(size 0.450088 0.450088)
			(layers "F.Cu" "F.Mask" "F.Paste")
			(net "M_H_CPU0_SA_CB<3>")
		)
		(pad "AL15" smd circle
			(at -20.999958 -12.510008 180)
			(size 0.450088 0.450088)
			(layers "F.Cu" "F.Mask" "F.Paste")
			(net "GND")
		)
		(pad "AL16" smd circle
			(at -20.059904 -12.510008 180)
			(size 0.450088 0.450088)
			(layers "F.Cu" "F.Mask" "F.Paste")
			(net "M_J_CPU0_SA_DQS_DP<4>")
		)
		(pad "AL17" smd circle
			(at -19.120104 -12.510008 180)
			(size 0.450088 0.450088)
			(layers "F.Cu" "F.Mask" "F.Paste")
			(net "M_J_CPU0_SA_CB<3>")
		)
		(pad "AL18" smd circle
			(at -18.18005 -12.510008 180)
			(size 0.450088 0.450088)
			(layers "F.Cu" "F.Mask" "F.Paste")
			(net "GND")
		)
		(pad "AL19" smd circle
			(at -17.239996 -12.510008 180)
			(size 0.450088 0.450088)
			(layers "F.Cu" "F.Mask" "F.Paste")
			(net "M_I_CPU0_SA_DQS_DP<4>")
		)
		(pad "AL20" smd circle
			(at -16.299942 -12.510008 180)
			(size 0.450088 0.450088)
			(layers "F.Cu" "F.Mask" "F.Paste")
			(net "GND")
		)
		(pad "AL21" smd circle
			(at -15.359888 -12.510008 180)
			(size 0.450088 0.450088)
			(layers "F.Cu" "F.Mask" "F.Paste")
			(net "M_I_CPU0_SA_CB<3>")
		)
		(pad "AL22" smd circle
			(at -14.420088 -12.510008 180)
			(size 0.450088 0.450088)
			(layers "F.Cu" "F.Mask" "F.Paste")
			(net "GND")
		)
		(pad "AL23" smd circle
			(at -13.480034 -12.510008 180)
			(size 0.450088 0.450088)
			(layers "F.Cu" "F.Mask" "F.Paste")
			(net "P5E_CPU0_G3_RX_DN<0>")
		)
		(pad "AL24" smd circle
			(at -12.53998 -12.510008 180)
			(size 0.450088 0.450088)
			(layers "F.Cu" "F.Mask" "F.Paste")
			(net "P5E_CPU0_G3_RX_DP<0>")
		)
		(pad "AL25" smd circle
			(at -11.599926 -12.510008 180)
			(size 0.450088 0.450088)
			(layers "F.Cu" "F.Mask" "F.Paste")
			(net "GND")
		)
		(pad "AL26" smd circle
			(at -10.659872 -12.510008 180)
			(size 0.450088 0.450088)
			(layers "F.Cu" "F.Mask" "F.Paste")
			(net "P5E_CPU0_G3_RX_DN<3>")
		)
		(pad "AL27" smd circle
			(at -9.720072 -12.510008 180)
			(size 0.450088 0.450088)
			(layers "F.Cu" "F.Mask" "F.Paste")
			(net "P5E_CPU0_G3_RX_DP<3>")
		)
		(pad "AL28" smd circle
			(at -8.780018 -12.510008 180)
			(size 0.450088 0.450088)
			(layers "F.Cu" "F.Mask" "F.Paste")
			(net "GND")
		)
		(pad "AL29" smd circle
			(at -7.839964 -12.510008 180)
			(size 0.450088 0.450088)
			(layers "F.Cu" "F.Mask" "F.Paste")
			(net "P5E_CPU0_G3_RX_DN<6>")
		)
		(pad "AL30" smd circle
			(at -6.89991 -12.510008 180)
			(size 0.450088 0.450088)
			(layers "F.Cu" "F.Mask" "F.Paste")
			(net "P5E_CPU0_G3_RX_DP<6>")
		)
		(pad "AL31" smd circle
			(at -5.96011 -12.510008 180)
			(size 0.450088 0.450088)
			(layers "F.Cu" "F.Mask" "F.Paste")
			(net "GND")
		)
		(pad "AL32" smd circle
			(at -5.020056 -12.510008 180)
			(size 0.450088 0.450088)
			(layers "F.Cu" "F.Mask" "F.Paste")
			(net "P5E_CPU0_G3_RX_DN<9>")
		)
		(pad "AL33" smd circle
			(at -4.080002 -12.510008 180)
			(size 0.450088 0.450088)
			(layers "F.Cu" "F.Mask" "F.Paste")
			(net "P5E_CPU0_G3_RX_DP<9>")
		)
		(pad "AL34" smd circle
			(at -3.139948 -12.510008 180)
			(size 0.450088 0.450088)
			(layers "F.Cu" "F.Mask" "F.Paste")
			(net "GND")
		)
		(pad "AL35" smd circle
			(at -2.199894 -12.510008 180)
			(size 0.450088 0.450088)
			(layers "F.Cu" "F.Mask" "F.Paste")
			(net "PVDDCR_CPU0_P0")
		)
		(pad "AL36" smd circle
			(at -1.260094 -12.510008 180)
			(size 0.450088 0.450088)
			(layers "F.Cu" "F.Mask" "F.Paste")
			(net "PVDDCR_CPU0_P0")
		)
		(pad "AL40" smd circle
			(at 1.560068 -12.510008 180)
			(size 0.450088 0.450088)
			(layers "F.Cu" "F.Mask" "F.Paste")
			(net "PVDDCR_CPU0_P0")
		)
		(pad "AL41" smd circle
			(at 2.500122 -12.510008 180)
			(size 0.450088 0.450088)
			(layers "F.Cu" "F.Mask" "F.Paste")
			(net "PVDDCR_CPU0_P0")
		)
		(pad "AL42" smd circle
			(at 3.439922 -12.510008 180)
			(size 0.450088 0.450088)
			(layers "F.Cu" "F.Mask" "F.Paste")
			(net "GND")
		)
		(pad "AL43" smd circle
			(at 4.379976 -12.510008 180)
			(size 0.450088 0.450088)
			(layers "F.Cu" "F.Mask" "F.Paste")
			(net "GMI_CPU0_G1_CPU1_G3_TX_DP<6>")
		)
		(pad "AL44" smd circle
			(at 5.32003 -12.510008 180)
			(size 0.450088 0.450088)
			(layers "F.Cu" "F.Mask" "F.Paste")
			(net "GMI_CPU0_G1_CPU1_G3_TX_DN<6>")
		)
		(pad "AL45" smd circle
			(at 6.260084 -12.510008 180)
			(size 0.450088 0.450088)
			(layers "F.Cu" "F.Mask" "F.Paste")
			(net "GND")
		)
		(pad "AL46" smd circle
			(at 7.199884 -12.510008 180)
			(size 0.450088 0.450088)
			(layers "F.Cu" "F.Mask" "F.Paste")
			(net "GMI_CPU0_G1_CPU1_G3_TX_DP<9>")
		)
		(pad "AL47" smd circle
			(at 8.139938 -12.510008 180)
			(size 0.450088 0.450088)
			(layers "F.Cu" "F.Mask" "F.Paste")
			(net "GMI_CPU0_G1_CPU1_G3_TX_DN<9>")
		)
		(pad "AL48" smd circle
			(at 9.079992 -12.510008 180)
			(size 0.450088 0.450088)
			(layers "F.Cu" "F.Mask" "F.Paste")
			(net "GND")
		)
		(pad "AL49" smd circle
			(at 10.020046 -12.510008 180)
			(size 0.450088 0.450088)
			(layers "F.Cu" "F.Mask" "F.Paste")
			(net "GMI_CPU0_G1_CPU1_G3_TX_DP<12>")
		)
		(pad "AL50" smd circle
			(at 10.9601 -12.510008 180)
			(size 0.450088 0.450088)
			(layers "F.Cu" "F.Mask" "F.Paste")
			(net "GMI_CPU0_G1_CPU1_G3_TX_DN<12>")
		)
		(pad "AL51" smd circle
			(at 11.8999 -12.510008 180)
			(size 0.450088 0.450088)
			(layers "F.Cu" "F.Mask" "F.Paste")
			(net "GND")
		)
		(pad "AL52" smd circle
			(at 12.839954 -12.510008 180)
			(size 0.450088 0.450088)
			(layers "F.Cu" "F.Mask" "F.Paste")
			(net "GMI_CPU0_G1_CPU1_G3_TX_DP<15>")
		)
		(pad "AL53" smd circle
			(at 13.780008 -12.510008 180)
			(size 0.450088 0.450088)
			(layers "F.Cu" "F.Mask" "F.Paste")
			(net "GMI_CPU0_G1_CPU1_G3_TX_DN<15>")
		)
		(pad "AL54" smd circle
			(at 14.720062 -12.510008 180)
			(size 0.450088 0.450088)
			(layers "F.Cu" "F.Mask" "F.Paste")
			(net "GND")
		)
		(pad "AL55" smd circle
			(at 15.660116 -12.510008 180)
			(size 0.450088 0.450088)
			(layers "F.Cu" "F.Mask" "F.Paste")
			(net "M_C_CPU0_SA_CB<3>")
		)
		(pad "AL56" smd circle
			(at 16.599916 -12.510008 180)
			(size 0.450088 0.450088)
			(layers "F.Cu" "F.Mask" "F.Paste")
			(net "GND")
		)
		(pad "AL57" smd circle
			(at 17.53997 -12.510008 180)
			(size 0.450088 0.450088)
			(layers "F.Cu" "F.Mask" "F.Paste")
			(net "M_C_CPU0_SA_DQS_DP<4>")
		)
		(pad "AL58" smd circle
			(at 18.480024 -12.510008 180)
			(size 0.450088 0.450088)
			(layers "F.Cu" "F.Mask" "F.Paste")
			(net "GND")
		)
		(pad "AL59" smd circle
			(at 19.420078 -12.510008 180)
			(size 0.450088 0.450088)
			(layers "F.Cu" "F.Mask" "F.Paste")
			(net "M_D_CPU0_SA_CB<3>")
		)
		(pad "AL60" smd circle
			(at 20.359878 -12.510008 180)
			(size 0.450088 0.450088)
			(layers "F.Cu" "F.Mask" "F.Paste")
			(net "M_D_CPU0_SA_DQS_DP<4>")
		)
		(pad "AL61" smd circle
			(at 21.299932 -12.510008 180)
			(size 0.450088 0.450088)
			(layers "F.Cu" "F.Mask" "F.Paste")
			(net "GND")
		)
		(pad "AL62" smd circle
			(at 22.239986 -12.510008 180)
			(size 0.450088 0.450088)
			(layers "F.Cu" "F.Mask" "F.Paste")
			(net "M_B_CPU0_SA_CB<3>")
		)
		(pad "AL63" smd circle
			(at 23.18004 -12.510008 180)
			(size 0.450088 0.450088)
			(layers "F.Cu" "F.Mask" "F.Paste")
			(net "GND")
		)
		(pad "AL64" smd circle
			(at 24.120094 -12.510008 180)
			(size 0.450088 0.450088)
			(layers "F.Cu" "F.Mask" "F.Paste")
			(net "M_B_CPU0_SA_DQS_DP<4>")
		)
		(pad "AL65" smd circle
			(at 25.059894 -12.510008 180)
			(size 0.450088 0.450088)
			(layers "F.Cu" "F.Mask" "F.Paste")
			(net "GND")
		)
		(pad "AL66" smd circle
			(at 25.999948 -12.510008 180)
			(size 0.450088 0.450088)
			(layers "F.Cu" "F.Mask" "F.Paste")
			(net "M_F_CPU0_SA_CB<3>")
		)
		(pad "AL67" smd circle
			(at 26.940002 -12.510008 180)
			(size 0.450088 0.450088)
			(layers "F.Cu" "F.Mask" "F.Paste")
			(net "M_F_CPU0_SA_DQS_DP<4>")
		)
		(pad "AL68" smd circle
			(at 27.880056 -12.510008 180)
			(size 0.450088 0.450088)
			(layers "F.Cu" "F.Mask" "F.Paste")
			(net "GND")
		)
		(pad "AL69" smd circle
			(at 28.82011 -12.510008 180)
			(size 0.450088 0.450088)
			(layers "F.Cu" "F.Mask" "F.Paste")
			(net "M_E_CPU0_SA_CB<3>")
		)
		(pad "AL70" smd circle
			(at 29.75991 -12.510008 180)
			(size 0.450088 0.450088)
			(layers "F.Cu" "F.Mask" "F.Paste")
			(net "GND")
		)
		(pad "AL71" smd circle
			(at 30.699964 -12.510008 180)
			(size 0.450088 0.450088)
			(layers "F.Cu" "F.Mask" "F.Paste")
			(net "M_E_CPU0_SA_DQS_DP<4>")
		)
		(pad "AL72" smd circle
			(at 31.640018 -12.510008 180)
			(size 0.450088 0.450088)
			(layers "F.Cu" "F.Mask" "F.Paste")
			(net "GND")
		)
		(pad "AL73" smd circle
			(at 32.580072 -12.510008 180)
			(size 0.450088 0.450088)
			(layers "F.Cu" "F.Mask" "F.Paste")
			(net "M_A_CPU0_SA_CB<3>")
		)
		(pad "AL74" smd circle
			(at 33.519872 -12.510008 180)
			(size 0.450088 0.450088)
			(layers "F.Cu" "F.Mask" "F.Paste")
			(net "M_A_CPU0_SA_DQS_DP<4>")
		)
		(pad "AL75" smd circle
			(at 34.459926 -12.510008 180)
			(size 0.450088 0.450088)
			(layers "F.Cu" "F.Mask" "F.Paste")
			(net "GND")
		)
		(pad "AM2" smd circle
			(at -33.690052 -11.700002 180)
			(size 0.450088 0.450088)
			(layers "F.Cu" "F.Mask" "F.Paste")
			(net "M_G_CPU0_SA_DQS_DN<4>")
		)
		(pad "AM3" smd circle
			(at -32.749998 -11.700002 180)
			(size 0.450088 0.450088)
			(layers "F.Cu" "F.Mask" "F.Paste")
			(net "GND")
		)
		(pad "AM4" smd circle
			(at -31.809944 -11.700002 180)
			(size 0.450088 0.450088)
			(layers "F.Cu" "F.Mask" "F.Paste")
			(net "M_G_CPU0_SA_DQS_DN<9>")
		)
		(pad "AM5" smd circle
			(at -30.86989 -11.700002 180)
			(size 0.450088 0.450088)
			(layers "F.Cu" "F.Mask" "F.Paste")
			(net "PVDDCR_SOC_P0")
		)
		(pad "AM6" smd circle
			(at -29.93009 -11.700002 180)
			(size 0.450088 0.450088)
			(layers "F.Cu" "F.Mask" "F.Paste")
			(net "M_K_CPU0_SA_DQS_DN<4>")
		)
		(pad "AM7" smd circle
			(at -28.990036 -11.700002 180)
			(size 0.450088 0.450088)
			(layers "F.Cu" "F.Mask" "F.Paste")
			(net "M_K_CPU0_SA_DQS_DN<9>")
		)
		(pad "AM8" smd circle
			(at -28.049982 -11.700002 180)
			(size 0.450088 0.450088)
			(layers "F.Cu" "F.Mask" "F.Paste")
			(net "GND")
		)
		(pad "AM9" smd circle
			(at -27.109928 -11.700002 180)
			(size 0.450088 0.450088)
			(layers "F.Cu" "F.Mask" "F.Paste")
			(net "M_L_CPU0_SA_DQS_DN<4>")
		)
		(pad "AM10" smd circle
			(at -26.170128 -11.700002 180)
			(size 0.450088 0.450088)
			(layers "F.Cu" "F.Mask" "F.Paste")
			(net "GND")
		)
		(pad "AM11" smd circle
			(at -25.230074 -11.700002 180)
			(size 0.450088 0.450088)
			(layers "F.Cu" "F.Mask" "F.Paste")
			(net "M_L_CPU0_SA_DQS_DN<9>")
		)
		(pad "AM12" smd circle
			(at -24.29002 -11.700002 180)
			(size 0.450088 0.450088)
			(layers "F.Cu" "F.Mask" "F.Paste")
			(net "PVDDCR_SOC_P0")
		)
		(pad "AM13" smd circle
			(at -23.349966 -11.700002 180)
			(size 0.450088 0.450088)
			(layers "F.Cu" "F.Mask" "F.Paste")
			(net "M_H_CPU0_SA_DQS_DN<4>")
		)
	)
)
